Created on Valor NPI 9.6 Update 2 - Netlist Compare Summary.
DATE :  30 Dec 2016
TIME :  13:29:47


     MISMATCH SUMMARY REPORT
     -----------------------

Job  : 15750-1_z11070266       Job  : 15750-1_z11070266
Step : db                      Step : db
Type : CAD                     Type : CURCAD

-----------------------------------------------

 Mismatch Type: shorted

   GND                   -   NET00001            
   AGND_P3V3_DEV         -    "                  

 Total : 1
-----------------------------------------------

 Mismatch Type: broken


 Total : 0
-----------------------------------------------

 Mismatch Type: missing


 Total : 0
-----------------------------------------------

 Mismatch Type: extra


 Total : 0
-----------------------------------------------
